(kicad_pcb
	(version 20260206)
	(generator "pcbnew")
	(generator_version "10.0")
	(general
		(thickness 1.6)
		(legacy_teardrops no)
	)
	(paper "A4")
	(title_block
		(title "v1-pdb — T6M_PDB_D_0927_0900.brd")
		(comment 1 "Open CloudServer (Microsoft) / footprints 9-12 of 321")
	)
	(layers
		(0 "F.Cu" signal "TOP")
		(4 "In1.Cu" signal "GND")
		(6 "In2.Cu" signal "IN1")
		(8 "In3.Cu" signal "VCC")
		(10 "In4.Cu" signal "VCC1")
		(12 "In5.Cu" signal "IN2")
		(14 "In6.Cu" signal "GND1")
		(2 "B.Cu" signal "BOTTOM")
		(9 "F.Adhes" user "F.Adhesive")
		(11 "B.Adhes" user "B.Adhesive")
		(13 "F.Paste" user "Package Geometry/Pastemask Top")
		(15 "B.Paste" user "Package Geometry/Pastemask Bottom")
		(5 "F.SilkS" user "Ref Des/Silkscreen Top")
		(7 "B.SilkS" user "Ref Des/Silkscreen Bottom")
		(1 "F.Mask" user "Board Geometry/Soldermask Top")
		(3 "B.Mask" user "Board Geometry/Soldermask Bottom")
		(17 "Dwgs.User" user "User.Drawings")
		(19 "Cmts.User" user "User.Comments")
		(21 "Eco1.User" user "User.Eco1")
		(23 "Eco2.User" user "User.Eco2")
		(25 "Edge.Cuts" user "Board Geometry/Outline")
		(27 "Margin" user)
		(31 "F.CrtYd" user "Package Geometry/Place Bound Top")
		(29 "B.CrtYd" user "Package Geometry/Place Bound Bottom")
		(35 "F.Fab" user "Ref Des/Assembly Top")
		(33 "B.Fab" user "Ref Des/Assembly Bottom")
	)
	(footprint ""
		(layer "F.Cu")
		(at 77.999844 -121.19991)
		(property "Reference" "H9"
			(at -9.877298 -3.685032 0)
			(unlocked yes)
			(layer "F.SilkS")
			(effects
				(font
					(size 0.7874 0.5842)
					(thickness 0.1524)
				)
				(justify left)
			)
		)
		(property "Value" ""
			(at 0 0 0)
			(layer "F.Fab")
			(effects
				(font
					(size 1.27 1.27)
				)
			)
		)
		(duplicate_pad_numbers_are_jumpers no)
		(fp_circle
			(center 0 0)
			(end 7.999984 0)
			(stroke
				(width 0.1524)
				(type default)
			)
			(fill no)
			(layer "F.SilkS")
		)
		(fp_arc
			(start 10.063734 10.724134)
			(mid -13.496547 -5.843072)
			(end 14.7066 0)
			(stroke
				(width 0.1524)
				(type default)
			)
			(layer "B.SilkS")
		)
		(fp_arc
			(start 14.7066 0)
			(mid 13.809901 5.056557)
			(end 11.22934 9.496552)
			(stroke
				(width 0.1524)
				(type default)
			)
			(layer "B.SilkS")
		)
		(fp_poly
			(pts
				(arc
					(start 5.0038 0)
					(mid -5.0038 0)
					(end 5.0038 0)
				)
			)
			(stroke
				(width 0)
				(type default)
			)
			(fill no)
			(layer "F.CrtYd")
		)
		(pad "" np_thru_hole circle
			(at 0 0)
			(size 4.0132 4.0132)
			(drill 4.0132)
			(layers "*.Cu" "*.Mask")
			(clearance 0.381)
			(thermal_gap 0.381)
		)
		(pad "2" thru_hole circle
			(at 0 -3.50012)
			(size 0.762 0.762)
			(drill 0.5588)
			(layers "*.Cu" "*.Mask")
			(remove_unused_layers no)
			(net "GND")
			(clearance 0.1524)
			(thermal_gap 0.1524)
		)
		(pad "3" thru_hole circle
			(at -2.500122 -2.500122)
			(size 0.762 0.762)
			(drill 0.5588)
			(layers "*.Cu" "*.Mask")
			(remove_unused_layers no)
			(net "GND")
			(clearance 0.1524)
			(thermal_gap 0.1524)
		)
		(pad "4" thru_hole circle
			(at -3.50012 0)
			(size 0.762 0.762)
			(drill 0.5588)
			(layers "*.Cu" "*.Mask")
			(remove_unused_layers no)
			(net "GND")
			(clearance 0.1524)
			(thermal_gap 0.1524)
		)
		(pad "5" thru_hole circle
			(at -2.500122 2.500122)
			(size 0.762 0.762)
			(drill 0.5588)
			(layers "*.Cu" "*.Mask")
			(remove_unused_layers no)
			(net "GND")
			(clearance 0.1524)
			(thermal_gap 0.1524)
		)
		(pad "6" thru_hole circle
			(at 0 3.50012)
			(size 0.762 0.762)
			(drill 0.5588)
			(layers "*.Cu" "*.Mask")
			(remove_unused_layers no)
			(net "GND")
			(clearance 0.1524)
			(thermal_gap 0.1524)
		)
		(pad "7" thru_hole circle
			(at 2.500122 2.500122)
			(size 0.762 0.762)
			(drill 0.5588)
			(layers "*.Cu" "*.Mask")
			(remove_unused_layers no)
			(net "GND")
			(clearance 0.1524)
			(thermal_gap 0.1524)
		)
		(pad "8" thru_hole circle
			(at 3.50012 0)
			(size 0.762 0.762)
			(drill 0.5588)
			(layers "*.Cu" "*.Mask")
			(remove_unused_layers no)
			(net "GND")
			(clearance 0.1524)
			(thermal_gap 0.1524)
		)
		(pad "9" thru_hole circle
			(at 2.500122 -2.500122)
			(size 0.762 0.762)
			(drill 0.5588)
			(layers "*.Cu" "*.Mask")
			(remove_unused_layers no)
			(net "GND")
			(clearance 0.1524)
			(thermal_gap 0.1524)
		)
		(zone
			(layer "F.Cu")
			(hatch none 0.5)
			(connect_pads
				(clearance 0)
			)
			(min_thickness 0.25)
			(keepout
				(tracks not_allowed)
				(vias allowed)
				(pads allowed)
				(copperpour not_allowed)
				(footprints allowed)
			)
			(placement
				(enabled no)
				(sheetname "")
			)
			(fill
				(thermal_gap 0.5)
				(thermal_bridge_width 0.5)
				(island_removal_mode 0)
			)
			(polygon
				(pts
					(arc
						(start 77.999844 -129.20091)
						(mid 69.998844 -121.19991)
						(end 77.999844 -113.19891)
					)
					(arc
						(start 77.999844 -113.19891)
						(mid 79.434944 -114.63401)
						(end 77.999844 -116.06911)
					)
					(arc
						(start 77.999844 -116.06911)
						(mid 72.869044 -121.19991)
						(end 77.999844 -126.33071)
					)
					(arc
						(start 77.999844 -126.33071)
						(mid 79.434944 -127.76581)
						(end 77.999844 -129.20091)
					)
				)
			)
		)
		(zone
			(layer "F.Cu")
			(hatch none 0.5)
			(connect_pads
				(clearance 0)
			)
			(min_thickness 0.25)
			(keepout
				(tracks not_allowed)
				(vias allowed)
				(pads allowed)
				(copperpour not_allowed)
				(footprints allowed)
			)
			(placement
				(enabled no)
				(sheetname "")
			)
			(fill
				(thermal_gap 0.5)
				(thermal_bridge_width 0.5)
				(island_removal_mode 0)
			)
			(polygon
				(pts
					(arc
						(start 77.999844 -129.20091)
						(mid 86.000844 -121.19991)
						(end 77.999844 -113.19891)
					)
					(arc
						(start 77.999844 -113.19891)
						(mid 76.564744 -114.63401)
						(end 77.999844 -116.06911)
					)
					(arc
						(start 77.999844 -116.06911)
						(mid 83.130644 -121.19991)
						(end 77.999844 -126.33071)
					)
					(arc
						(start 77.999844 -126.33071)
						(mid 76.564744 -127.76581)
						(end 77.999844 -129.20091)
					)
				)
			)
		)
		(zone
			(layers "F.Cu" "B.Cu" "In1.Cu" "In2.Cu" "In3.Cu" "In4.Cu" "In5.Cu" "In6.Cu")
			(hatch none 0.5)
			(connect_pads
				(clearance 0)
			)
			(min_thickness 0.25)
			(keepout
				(tracks not_allowed)
				(vias allowed)
				(pads allowed)
				(copperpour not_allowed)
				(footprints allowed)
			)
			(placement
				(enabled no)
				(sheetname "")
			)
			(fill
				(thermal_gap 0.5)
				(thermal_bridge_width 0.5)
				(island_removal_mode 0)
			)
			(polygon
				(pts
					(arc
						(start 80.511904 -121.19991)
						(mid 75.487784 -121.19991)
						(end 80.511904 -121.19991)
					)
				)
			)
		)
	)
	(footprint ""
		(layer "F.Cu")
		(at 4.50469 -494.611914)
		(property "Reference" "J22"
			(at 2.474976 -5.752846 0)
			(unlocked yes)
			(layer "F.SilkS")
			(effects
				(font
					(size 0.7874 0.5842)
					(thickness 0.1524)
				)
				(justify left)
			)
		)
		(property "Value" ""
			(at 0 0 0)
			(layer "F.Fab")
			(effects
				(font
					(size 1.27 1.27)
				)
			)
		)
		(duplicate_pad_numbers_are_jumpers no)
		(fp_line
			(start -3.370072 -3.81)
			(end 12.260072 -3.81)
			(stroke
				(width 0.1524)
				(type default)
			)
			(layer "F.SilkS")
		)
		(fp_line
			(start -3.370072 12.830048)
			(end -3.370072 -3.81)
			(stroke
				(width 0.1524)
				(type default)
			)
			(layer "F.SilkS")
		)
		(fp_line
			(start 12.260072 -3.81)
			(end 12.260072 12.830048)
			(stroke
				(width 0.1524)
				(type default)
			)
			(layer "F.SilkS")
		)
		(fp_line
			(start 12.260072 12.830048)
			(end -3.370072 12.830048)
			(stroke
				(width 0.1524)
				(type default)
			)
			(layer "F.SilkS")
		)
		(fp_poly
			(pts
				(xy -3.451606 -0.016764) (xy -4.255262 0.385064) (xy -4.255262 -0.418592)
			)
			(stroke
				(width 0)
				(type default)
			)
			(fill yes)
			(layer "F.SilkS")
		)
		(fp_poly
			(pts
				(xy -0.762 0.762) (xy 8.382 0.762) (xy 8.382 -1.8034) (xy 9.652 -1.8034) (xy 9.652 -3.302) (xy 0.508 -3.302)
				(xy 0.508 -0.762) (xy -0.762 -0.762)
			)
			(stroke
				(width 0)
				(type default)
			)
			(fill no)
			(layer "B.CrtYd")
		)
		(fp_poly
			(pts
				(arc
					(start 0.6604 6.35)
					(mid -3.2004 6.35)
					(end 0.6604 6.35)
				)
			)
			(stroke
				(width 0)
				(type default)
			)
			(fill no)
			(layer "B.CrtYd")
		)
		(fp_poly
			(pts
				(arc
					(start 12.0904 6.35)
					(mid 8.2296 6.35)
					(end 12.0904 6.35)
				)
			)
			(stroke
				(width 0)
				(type default)
			)
			(fill no)
			(layer "B.CrtYd")
		)
		(fp_poly
			(pts
				(xy -3.370072 12.830048) (xy 12.260072 12.830048) (xy 12.260072 -3.81) (xy -3.370072 -3.81)
			)
			(stroke
				(width 0)
				(type default)
			)
			(fill no)
			(layer "F.CrtYd")
		)
		(fp_line
			(start -3.370072 -3.81)
			(end 12.260072 -3.81)
			(stroke
				(width 0.1)
				(type default)
			)
			(layer "F.Fab")
		)
		(fp_line
			(start -3.370072 12.830048)
			(end -3.370072 -3.81)
			(stroke
				(width 0.1)
				(type default)
			)
			(layer "F.Fab")
		)
		(fp_line
			(start 12.260072 -3.81)
			(end 12.260072 12.830048)
			(stroke
				(width 0.1)
				(type default)
			)
			(layer "F.Fab")
		)
		(fp_line
			(start 12.260072 12.830048)
			(end -3.370072 12.830048)
			(stroke
				(width 0.1)
				(type default)
			)
			(layer "F.Fab")
		)
		(fp_poly
			(pts
				(xy -3.576828 0) (xy -5.0038 0.713486) (xy -5.0038 -0.713486)
			)
			(stroke
				(width 0)
				(type default)
			)
			(fill yes)
			(layer "F.Fab")
		)
		(fp_text user "2"
			(at -3.828796 -3.314446 0)
			(unlocked yes)
			(layer "F.SilkS")
			(effects
				(font
					(size 0.7874 0.5842)
					(thickness 0.1524)
				)
			)
		)
		(fp_text user "1"
			(at -3.777996 -1.815846 0)
			(unlocked yes)
			(layer "F.SilkS")
			(effects
				(font
					(size 0.7874 0.5842)
					(thickness 0.1524)
				)
			)
		)
		(fp_text user "8"
			(at 12.7762 -2.555748 0)
			(unlocked yes)
			(layer "F.SilkS")
			(effects
				(font
					(size 0.7874 0.5842)
					(thickness 0.1524)
				)
			)
		)
		(fp_text user "7"
			(at 12.7762 -0.091948 0)
			(unlocked yes)
			(layer "F.SilkS")
			(effects
				(font
					(size 0.7874 0.5842)
					(thickness 0.1524)
				)
			)
		)
		(fp_text user "1"
			(at -1.2954 0.085852 0)
			(unlocked yes)
			(layer "B.SilkS")
			(effects
				(font
					(size 0.7874 0.5842)
					(thickness 0.1524)
				)
				(justify mirror)
			)
		)
		(fp_text user "2"
			(at 0 -2.581148 0)
			(unlocked yes)
			(layer "B.SilkS")
			(effects
				(font
					(size 0.7874 0.5842)
					(thickness 0.1524)
				)
				(justify mirror)
			)
		)
		(fp_text user "7"
			(at 8.8138 0.238252 0)
			(unlocked yes)
			(layer "B.SilkS")
			(effects
				(font
					(size 0.7874 0.5842)
					(thickness 0.1524)
				)
				(justify mirror)
			)
		)
		(fp_text user "8"
			(at 10.0838 -2.403348 0)
			(unlocked yes)
			(layer "B.SilkS")
			(effects
				(font
					(size 0.7874 0.5842)
					(thickness 0.1524)
				)
				(justify mirror)
			)
		)
		(fp_text user "1"
			(at -1.2954 0.085852 0)
			(unlocked yes)
			(layer "B.Fab")
			(effects
				(font
					(size 0.7874 0.5842)
					(thickness 0.000001)
				)
				(justify mirror)
			)
		)
		(fp_text user "2"
			(at 0 -2.581148 0)
			(unlocked yes)
			(layer "B.Fab")
			(effects
				(font
					(size 0.7874 0.5842)
					(thickness 0.000001)
				)
				(justify mirror)
			)
		)
		(fp_text user "7"
			(at 8.8138 0.238252 0)
			(unlocked yes)
			(layer "B.Fab")
			(effects
				(font
					(size 0.7874 0.5842)
					(thickness 0.000001)
				)
				(justify mirror)
			)
		)
		(fp_text user "8"
			(at 10.0838 -2.403348 0)
			(unlocked yes)
			(layer "B.Fab")
			(effects
				(font
					(size 0.7874 0.5842)
					(thickness 0.000001)
				)
				(justify mirror)
			)
		)
		(fp_text user "2"
			(at -3.9624 -2.428748 0)
			(unlocked yes)
			(layer "F.Fab")
			(effects
				(font
					(size 0.7874 0.5842)
					(thickness 0.000001)
				)
			)
		)
		(fp_text user "1"
			(at -3.9116 -0.930148 0)
			(unlocked yes)
			(layer "F.Fab")
			(effects
				(font
					(size 0.7874 0.5842)
					(thickness 0.000001)
				)
			)
		)
		(fp_text user "8"
			(at 12.7762 -2.555748 0)
			(unlocked yes)
			(layer "F.Fab")
			(effects
				(font
					(size 0.7874 0.5842)
					(thickness 0.000001)
				)
			)
		)
		(fp_text user "7"
			(at 12.7762 -0.091948 0)
			(unlocked yes)
			(layer "F.Fab")
			(effects
				(font
					(size 0.7874 0.5842)
					(thickness 0.000001)
				)
			)
		)
		(pad "" np_thru_hole circle
			(at -1.27 6.35)
			(size 3.3528 3.3528)
			(drill 3.3528)
			(layers "*.Cu" "*.Mask")
			(clearance 0.381)
			(thermal_gap 0.381)
		)
		(pad "" np_thru_hole circle
			(at 10.16 6.35)
			(size 3.3528 3.3528)
			(drill 3.3528)
			(layers "*.Cu" "*.Mask")
			(clearance 0.381)
			(thermal_gap 0.381)
		)
		(pad "1" thru_hole rect
			(at 0 0)
			(size 1.397 1.397)
			(drill 0.9906)
			(layers "*.Cu" "*.Mask")
			(remove_unused_layers no)
			(net "UART_RTS_RP5_L_N")
			(clearance 0.0508)
			(thermal_gap 0.0508)
			(padstack
				(mode front_inner_back)
				(layer "Inner"
					(shape circle)
					(size 1.397 1.397)
					(clearance 0.0508)
				)
				(layer "B.Cu"
					(shape rect)
					(size 1.397 1.397)
					(clearance 0.0508)
				)
			)
		)
		(pad "2" thru_hole circle
			(at 1.27 -2.54)
			(size 1.397 1.397)
			(drill 0.9906)
			(layers "*.Cu" "*.Mask")
			(remove_unused_layers no)
			(net "UART_DSR_RP5_L")
			(clearance 0.0508)
			(thermal_gap 0.0508)
		)
		(pad "3" thru_hole circle
			(at 2.54 0)
			(size 1.397 1.397)
			(drill 0.9906)
			(layers "*.Cu" "*.Mask")
			(remove_unused_layers no)
			(net "UART_RX_RP5_L")
			(clearance 0.0508)
			(thermal_gap 0.0508)
		)
		(pad "4" thru_hole circle
			(at 3.81 -2.54)
			(size 1.397 1.397)
			(drill 0.9906)
			(layers "*.Cu" "*.Mask")
			(remove_unused_layers no)
			(net "UART_RI_RP5_L_N")
			(clearance 0.0508)
			(thermal_gap 0.0508)
		)
		(pad "5" thru_hole circle
			(at 5.08 0)
			(size 1.397 1.397)
			(drill 0.9906)
			(layers "*.Cu" "*.Mask")
			(remove_unused_layers no)
			(net "GND")
			(clearance 0.0508)
			(thermal_gap 0.0508)
		)
		(pad "6" thru_hole circle
			(at 6.35 -2.54)
			(size 1.397 1.397)
			(drill 0.9906)
			(layers "*.Cu" "*.Mask")
			(remove_unused_layers no)
			(net "UART_TX_RP5_L")
			(clearance 0.0508)
			(thermal_gap 0.0508)
		)
		(pad "7" thru_hole circle
			(at 7.62 0)
			(size 1.397 1.397)
			(drill 0.9906)
			(layers "*.Cu" "*.Mask")
			(remove_unused_layers no)
			(net "UART_DTR_RP5_L_N")
			(clearance 0.0508)
			(thermal_gap 0.0508)
		)
		(pad "8" thru_hole circle
			(at 8.89 -2.54)
			(size 1.397 1.397)
			(drill 0.9906)
			(layers "*.Cu" "*.Mask")
			(remove_unused_layers no)
			(net "UART_CTS_RP5_L_N")
			(clearance 0.0508)
			(thermal_gap 0.0508)
		)
		(zone
			(layers "F.Cu" "B.Cu" "In1.Cu" "In2.Cu" "In3.Cu" "In4.Cu" "In5.Cu" "In6.Cu")
			(hatch none 0.5)
			(connect_pads
				(clearance 0)
			)
			(min_thickness 0.25)
			(keepout
				(tracks not_allowed)
				(vias allowed)
				(pads allowed)
				(copperpour not_allowed)
				(footprints allowed)
			)
			(placement
				(enabled no)
				(sheetname "")
			)
			(fill
				(thermal_gap 0.5)
				(thermal_bridge_width 0.5)
				(island_removal_mode 0)
			)
			(polygon
				(pts
					(arc
						(start 5.31749 -488.261914)
						(mid 1.15189 -488.261914)
						(end 5.31749 -488.261914)
					)
				)
			)
		)
		(zone
			(layers "F.Cu" "B.Cu" "In1.Cu" "In2.Cu" "In3.Cu" "In4.Cu" "In5.Cu" "In6.Cu")
			(hatch none 0.5)
			(connect_pads
				(clearance 0)
			)
			(min_thickness 0.25)
			(keepout
				(tracks not_allowed)
				(vias allowed)
				(pads allowed)
				(copperpour not_allowed)
				(footprints allowed)
			)
			(placement
				(enabled no)
				(sheetname "")
			)
			(fill
				(thermal_gap 0.5)
				(thermal_bridge_width 0.5)
				(island_removal_mode 0)
			)
			(polygon
				(pts
					(arc
						(start 16.74749 -488.261914)
						(mid 12.58189 -488.261914)
						(end 16.74749 -488.261914)
					)
				)
			)
		)
	)
	(footprint ""
		(layer "F.Cu")
		(at 69.982334 -370.601748 -90)
		(property "Reference" "C58"
			(at -2.675128 0.148844 90)
			(unlocked yes)
			(layer "F.SilkS")
			(effects
				(font
					(size 0.7874 0.5842)
					(thickness 0.1524)
				)
				(justify left)
			)
		)
		(property "Value" ""
			(at 0 0 270)
			(layer "F.Fab")
			(effects
				(font
					(size 1.27 1.27)
				)
			)
		)
		(duplicate_pad_numbers_are_jumpers no)
		(fp_line
			(start -0.7874 0.4064)
			(end -0.7874 -0.4064)
			(stroke
				(width 0.1524)
				(type default)
			)
			(layer "F.SilkS")
		)
		(fp_line
			(start 0.7874 0.4064)
			(end -0.7874 0.4064)
			(stroke
				(width 0.1524)
				(type default)
			)
			(layer "F.SilkS")
		)
		(fp_line
			(start 0 0.381)
			(end 0 -0.381)
			(stroke
				(width 0.1524)
				(type default)
			)
			(layer "F.SilkS")
		)
		(fp_line
			(start -0.7874 -0.4064)
			(end 0.7874 -0.4064)
			(stroke
				(width 0.1524)
				(type default)
			)
			(layer "F.SilkS")
		)
		(fp_line
			(start 0.7874 -0.4064)
			(end 0.7874 0.4064)
			(stroke
				(width 0.1524)
				(type default)
			)
			(layer "F.SilkS")
		)
		(fp_poly
			(pts
				(xy -0.5334 0.254) (xy -0.635 0.254) (xy -0.635 0.2286) (xy -0.635 -0.254) (xy -0.5334 -0.254) (xy -0.5334 -0.2794)
				(xy 0.5334 -0.2794) (xy 0.5334 -0.254) (xy 0.635 -0.254) (xy 0.635 0.254) (xy 0.5334 0.254) (xy 0.5334 0.2794)
				(xy -0.508 0.2794) (xy -0.5334 0.2794)
			)
			(stroke
				(width 0)
				(type default)
			)
			(fill no)
			(layer "F.CrtYd")
		)
		(pad "1" smd rect
			(at 0.40005 0 270)
			(size 0.4572 0.508)
			(layers "F.Cu" "F.Mask" "F.Paste")
			(net "P12V")
		)
		(pad "2" smd rect
			(at -0.40005 0 270)
			(size 0.4572 0.508)
			(layers "F.Cu" "F.Mask" "F.Paste")
			(net "GND")
		)
	)
	(footprint ""
		(layer "F.Cu")
		(at 39.849552 -17.30502 180)
		(property "Reference" "R12"
			(at -1.74498 -0.093472 0)
			(unlocked yes)
			(layer "F.SilkS")
			(effects
				(font
					(size 0.7874 0.5842)
					(thickness 0.1524)
				)
				(justify left)
			)
		)
		(property "Value" ""
			(at 0 0 180)
			(layer "F.Fab")
			(effects
				(font
					(size 1.27 1.27)
				)
			)
		)
		(duplicate_pad_numbers_are_jumpers no)
		(fp_line
			(start 0.7874 0.4064)
			(end -0.7874 0.4064)
			(stroke
				(width 0.1524)
				(type default)
			)
			(layer "F.SilkS")
		)
		(fp_line
			(start 0.7874 -0.4064)
			(end 0.7874 0.4064)
			(stroke
				(width 0.1524)
				(type default)
			)
			(layer "F.SilkS")
		)
		(fp_line
			(start -0.7874 0.4064)
			(end -0.7874 -0.4064)
			(stroke
				(width 0.1524)
				(type default)
			)
			(layer "F.SilkS")
		)
		(fp_line
			(start -0.7874 -0.4064)
			(end 0.7874 -0.4064)
			(stroke
				(width 0.1524)
				(type default)
			)
			(layer "F.SilkS")
		)
		(fp_poly
			(pts
				(xy -0.508 0.2794) (xy -0.508 0.2286) (xy -0.635 0.2286) (xy -0.635 -0.254) (xy -0.5334 -0.254)
				(xy -0.5334 -0.2794) (xy 0.5334 -0.2794) (xy 0.5334 -0.254) (xy 0.635 -0.254) (xy 0.635 0.254) (xy 0.5334 0.254)
				(xy 0.5334 0.2794)
			)
			(stroke
				(width 0)
				(type default)
			)
			(fill no)
			(layer "F.CrtYd")
		)
		(pad "1" smd rect
			(at 0.40005 0 180)
			(size 0.4572 0.508)
			(layers "F.Cu" "F.Mask" "F.Paste")
			(net "PSU1_AD0")
		)
		(pad "2" smd rect
			(at -0.40005 0 180)
			(size 0.4572 0.508)
			(layers "F.Cu" "F.Mask" "F.Paste")
			(net "GND")
		)
	)
)
